# TIMECARD (Time Appliance Project (Time Card)) — schematic netlist excerpt (pin names and nets, part order shuffled) for the footprints in the layout excerpt that follows; sources: Cadence DE-HDL packaged netlist, KiCad conversion of R4006-B0001-02_R01.brd

C140  CAPACITOR  0.1UF 10V 10%  pkg SMC_0402R_H022  page 14 : \1\ = XP3R3V_FPGA ; \2\ = SG
R405  RESISTOR  10KOHM 1%  pkg SMC_0402R_H016  page 10 : \1\ = XP3R3V_FPGA ; \2\ = FPGA_TDI

(kicad_pcb
	(version 20260206)
	(generator "pcbnew")
	(generator_version "10.0")
	(general
		(thickness 1.6)
		(legacy_teardrops no)
	)
	(paper "A4")
	(title_block
		(title "timecard-production-celestica-r4006 — R4006-B0001-02_R01.brd")
		(comment 1 "Time Appliance Project (Time Card) / footprints 1071-1072 of 1113")
	)
	(layers
		(0 "F.Cu" signal "TOP")
		(4 "In1.Cu" signal "L02_GND1")
		(6 "In2.Cu" signal "L03_SIG1")
		(8 "In3.Cu" signal "L04_GND2")
		(10 "In4.Cu" signal "L05_VCC1")
		(12 "In5.Cu" signal "L06_VCC2")
		(14 "In6.Cu" signal "L07_GND3")
		(16 "In7.Cu" signal "L08_SIG2")
		(18 "In8.Cu" signal "L09_GND4")
		(2 "B.Cu" signal "BOTTOM")
		(9 "F.Adhes" user "F.Adhesive")
		(11 "B.Adhes" user "B.Adhesive")
		(13 "F.Paste" user "Package Geometry/Pastemask Top")
		(15 "B.Paste" user "Package Geometry/Pastemask Bottom")
		(5 "F.SilkS" user "Ref Des/Silkscreen Top")
		(7 "B.SilkS" user "Ref Des/Silkscreen Bottom")
		(1 "F.Mask" user "Board Geometry/Soldermask Top")
		(3 "B.Mask" user "Board Geometry/Soldermask Bottom")
		(17 "Dwgs.User" user "User.Drawings")
		(19 "Cmts.User" user "User.Comments")
		(21 "Eco1.User" user "User.Eco1")
		(23 "Eco2.User" user "User.Eco2")
		(25 "Edge.Cuts" user "Board Geometry/Outline")
		(27 "Margin" user)
		(31 "F.CrtYd" user "Package Geometry/Place Bound Top")
		(29 "B.CrtYd" user "Package Geometry/Place Bound Bottom")
		(35 "F.Fab" user "Ref Des/Assembly Top")
		(33 "B.Fab" user "Ref Des/Assembly Bottom")
	)
	(footprint ""
		(layer "B.Cu")
		(at 138.4808 -77.216 90)
		(property "Reference" "R405"
			(at 1.778 -1.10617 270)
			(unlocked yes)
			(layer "B.SilkS")
			(effects
				(font
					(size 0.7874 0.5842)
					(thickness 0.1524)
				)
				(justify mirror)
			)
		)
		(property "Value" "VAL*"
			(at -0.02032 2.13233 90)
			(unlocked yes)
			(layer "B.Fab")
			(hide yes)
			(effects
				(font
					(size 0.7874 0.5842)
					(thickness 0.1524)
				)
				(justify mirror)
			)
		)
		(property "Device Type" "RESISTOR-G155-11002-01,10KOHM,A"
			(at -0.008382 1.210564 90)
			(unlocked yes)
			(layer "B.Fab")
			(hide yes)
			(effects
				(font
					(size 0.7874 0.5842)
					(thickness 0.1524)
				)
				(justify mirror)
			)
		)
		(property "User Part Number" "PARTNUM*"
			(at -0.02032 4.024884 90)
			(unlocked yes)
			(layer "Cmts.User")
			(hide yes)
			(effects
				(font
					(size 0.7874 0.5842)
					(thickness 0.1524)
				)
				(justify mirror)
			)
		)
		(property "Tolerance" "TOL*"
			(at -0.044704 3.05435 90)
			(unlocked yes)
			(layer "Cmts.User")
			(hide yes)
			(effects
				(font
					(size 0.7874 0.5842)
					(thickness 0.1524)
				)
				(justify mirror)
			)
		)
		(duplicate_pad_numbers_are_jumpers no)
		(fp_line
			(start 1.143 -0.5588)
			(end 1.143 0.5588)
			(stroke
				(width 0.1)
				(type default)
			)
			(layer "B.SilkS")
		)
		(fp_line
			(start -1.143 -0.5588)
			(end 1.143 -0.5588)
			(stroke
				(width 0.1)
				(type default)
			)
			(layer "B.SilkS")
		)
		(fp_line
			(start 1.143 0.5588)
			(end -1.143 0.5588)
			(stroke
				(width 0.1)
				(type default)
			)
			(layer "B.SilkS")
		)
		(fp_line
			(start -1.143 0.5588)
			(end -1.143 -0.5588)
			(stroke
				(width 0.1)
				(type default)
			)
			(layer "B.SilkS")
		)
		(fp_rect
			(start 1.143 0.5588)
			(end -1.143 -0.5588)
			(stroke
				(width 0)
				(type default)
			)
			(fill no)
			(layer "B.CrtYd")
		)
		(fp_line
			(start 0.508 -0.3048)
			(end 0.508 0.3048)
			(stroke
				(width 0.1)
				(type default)
			)
			(layer "B.Fab")
		)
		(fp_line
			(start -0.508 -0.3048)
			(end 0.508 -0.3048)
			(stroke
				(width 0.1)
				(type default)
			)
			(layer "B.Fab")
		)
		(fp_line
			(start 0.508 0.3048)
			(end -0.508 0.3048)
			(stroke
				(width 0.1)
				(type default)
			)
			(layer "B.Fab")
		)
		(fp_line
			(start -0.508 0.3048)
			(end -0.508 -0.3048)
			(stroke
				(width 0.1)
				(type default)
			)
			(layer "B.Fab")
		)
		(pad "1" smd rect
			(at 0.5334 0 270)
			(size 0.7112 0.6096)
			(layers "B.Cu" "B.Mask" "B.Paste")
			(net "XP3R3V_FPGA")
		)
		(pad "2" smd rect
			(at -0.5334 0 270)
			(size 0.7112 0.6096)
			(layers "B.Cu" "B.Mask" "B.Paste")
			(net "FPGA_TDI")
		)
		(zone
			(layer "B.Cu")
			(hatch none 0.5)
			(connect_pads
				(clearance 0)
			)
			(min_thickness 0.25)
			(keepout
				(tracks not_allowed)
				(vias allowed)
				(pads allowed)
				(copperpour not_allowed)
				(footprints allowed)
			)
			(placement
				(enabled no)
				(sheetname "")
			)
			(fill
				(thermal_gap 0.5)
				(thermal_bridge_width 0.5)
				(island_removal_mode 0)
			)
			(polygon
				(pts
					(xy 138.7856 -77.2922) (xy 138.176 -77.2922) (xy 138.176 -77.1398) (xy 138.7856 -77.1398)
				)
			)
		)
		(zone
			(layer "B.Cu")
			(hatch none 0.5)
			(connect_pads
				(clearance 0)
			)
			(min_thickness 0.25)
			(keepout
				(tracks allowed)
				(vias not_allowed)
				(pads allowed)
				(copperpour not_allowed)
				(footprints allowed)
			)
			(placement
				(enabled no)
				(sheetname "")
			)
			(fill
				(thermal_gap 0.5)
				(thermal_bridge_width 0.5)
				(island_removal_mode 0)
			)
			(polygon
				(pts
					(xy 138.7856 -77.2922) (xy 138.176 -77.2922) (xy 138.176 -77.1398) (xy 138.7856 -77.1398)
				)
			)
		)
	)
	(footprint ""
		(layer "B.Cu")
		(at 99.846892 -53.322982 90)
		(property "Reference" "C140"
			(at 1.414018 1.086358 270)
			(unlocked yes)
			(layer "B.SilkS")
			(effects
				(font
					(size 0.635 0.4064)
					(thickness 0.1524)
				)
				(justify mirror)
			)
		)
		(property "Value" "VAL*"
			(at 0 3.718306 90)
			(unlocked yes)
			(layer "B.Fab")
			(hide yes)
			(effects
				(font
					(size 0.7874 0.5842)
					(thickness 0.127)
				)
				(justify mirror)
			)
		)
		(property "Tolerance" "TOL*"
			(at 0 4.861306 90)
			(unlocked yes)
			(layer "Cmts.User")
			(hide yes)
			(effects
				(font
					(size 0.7874 0.5842)
					(thickness 0.127)
				)
				(justify mirror)
			)
		)
		(property "User Part Number" "PARTNUM*"
			(at 0 2.575306 90)
			(unlocked yes)
			(layer "Cmts.User")
			(hide yes)
			(effects
				(font
					(size 0.7874 0.5842)
					(thickness 0.127)
				)
				(justify mirror)
			)
		)
		(property "Device Type" "CAPACITOR-G105-0B104-CK,0.1UF,A"
			(at 0 1.432306 90)
			(unlocked yes)
			(layer "B.Fab")
			(hide yes)
			(effects
				(font
					(size 0.7874 0.5842)
					(thickness 0.127)
				)
				(justify mirror)
			)
		)
		(duplicate_pad_numbers_are_jumpers no)
		(fp_line
			(start 0.970026 -0.4699)
			(end -0.970026 -0.4699)
			(stroke
				(width 0.1)
				(type default)
			)
			(layer "B.SilkS")
		)
		(fp_line
			(start -0.970026 -0.4699)
			(end -0.970026 0.4699)
			(stroke
				(width 0.1)
				(type default)
			)
			(layer "B.SilkS")
		)
		(fp_line
			(start 0.970026 0.4699)
			(end 0.970026 -0.4699)
			(stroke
				(width 0.1)
				(type default)
			)
			(layer "B.SilkS")
		)
		(fp_line
			(start -0.970026 0.4699)
			(end 0.970026 0.4699)
			(stroke
				(width 0.1)
				(type default)
			)
			(layer "B.SilkS")
		)
		(fp_poly
			(pts
				(xy 0.970026 0.4699) (xy -0.970026 0.4699) (xy -0.970026 -0.4699) (xy 0.970026 -0.4699)
			)
			(stroke
				(width 0)
				(type default)
			)
			(fill no)
			(layer "B.CrtYd")
		)
		(fp_line
			(start 0.508 -0.3048)
			(end -0.508 -0.3048)
			(stroke
				(width 0.1)
				(type default)
			)
			(layer "B.Fab")
		)
		(fp_line
			(start -0.508 -0.3048)
			(end -0.508 0.3048)
			(stroke
				(width 0.1)
				(type default)
			)
			(layer "B.Fab")
		)
		(fp_line
			(start 0.508 0.3048)
			(end 0.508 -0.3048)
			(stroke
				(width 0.1)
				(type default)
			)
			(layer "B.Fab")
		)
		(fp_line
			(start -0.508 0.3048)
			(end 0.508 0.3048)
			(stroke
				(width 0.1)
				(type default)
			)
			(layer "B.Fab")
		)
		(pad "1" smd circle
			(at 0.500126 0 270)
			(size 0.635 0.635)
			(layers "B.Cu" "B.Mask" "B.Paste")
			(net "XP3R3V_FPGA")
		)
		(pad "2" smd circle
			(at -0.500126 0 270)
			(size 0.635 0.635)
			(layers "B.Cu" "B.Mask" "B.Paste")
			(net "SG")
		)
	)
)
